# BASEBOARD_FAB2 (Tioga Pass) — schematic netlist excerpt (pin names and nets, part order shuffled) for the footprints in the layout excerpt that follows; sources: Cadence DE-HDL packaged netlist, KiCad conversion of Wiwynn_Tioga_Pass_MB.brd

C6T2  CAP  10UF 16V 10% X7R  pkg 0805  page 197 : A = P12V_NVDIMM_ABC ; B = GND
C2U16  CAP  0.22UF 16V 10% X7R  pkg 0402  page 107 : A = P3E_CPU0_PE1_PCH_RXN<6> ; B = P3E_CPU0_PE1_SS_RXN<6>
C8U10  CAP  100UF 4V 20% X5R  pkg 0805  page 229 : A = PVTT_GHJ ; B = GND

(kicad_pcb
	(version 20260206)
	(generator "pcbnew")
	(generator_version "10.0")
	(general
		(thickness 1.6)
		(legacy_teardrops no)
	)
	(paper "A4")
	(title_block
		(title "Wiwynn_Tioga_Pass_MB.brd")
		(comment 1 "Tioga Pass / footprints 3679-3681 of 4770")
	)
	(layers
		(0 "F.Cu" signal "TOP")
		(4 "In1.Cu" signal "L2GND")
		(6 "In2.Cu" signal "L3")
		(8 "In3.Cu" signal "L4GND")
		(10 "In4.Cu" signal "L5")
		(12 "In5.Cu" signal "L6GND")
		(14 "In6.Cu" signal "L7VCC")
		(16 "In7.Cu" signal "L8VCC")
		(18 "In8.Cu" signal "L9GND")
		(20 "In9.Cu" signal "L10")
		(22 "In10.Cu" signal "L11GND")
		(24 "In11.Cu" signal "L12")
		(26 "In12.Cu" signal "L13GND")
		(2 "B.Cu" signal "BOTTOM")
		(9 "F.Adhes" user "F.Adhesive")
		(11 "B.Adhes" user "B.Adhesive")
		(13 "F.Paste" user "Package Geometry/Pastemask Top")
		(15 "B.Paste" user "Package Geometry/Pastemask Bottom")
		(5 "F.SilkS" user "Ref Des/Silkscreen Top")
		(7 "B.SilkS" user "Ref Des/Silkscreen Bottom")
		(1 "F.Mask" user "Board Geometry/Soldermask Top")
		(3 "B.Mask" user "Board Geometry/Soldermask Bottom")
		(17 "Dwgs.User" user "User.Drawings")
		(19 "Cmts.User" user "User.Comments")
		(21 "Eco1.User" user "User.Eco1")
		(23 "Eco2.User" user "User.Eco2")
		(25 "Edge.Cuts" user "Board Geometry/Outline")
		(27 "Margin" user)
		(31 "F.CrtYd" user "Package Geometry/Place Bound Top")
		(29 "B.CrtYd" user "Package Geometry/Place Bound Bottom")
		(35 "F.Fab" user "Ref Des/Assembly Top")
		(33 "B.Fab" user "Ref Des/Assembly Bottom")
	)
	(footprint ""
		(layer "B.Cu")
		(at 193.092832 -17.723612 -90)
		(property "Reference" "C6T2"
			(at 0 0 90)
			(layer "B.SilkS")
			(hide yes)
			(effects
				(font
					(size 1.27 1.27)
				)
				(justify mirror)
			)
		)
		(property "Value" ""
			(at 0 0 90)
			(layer "B.Fab")
			(effects
				(font
					(size 1.27 1.27)
				)
				(justify mirror)
			)
		)
		(duplicate_pad_numbers_are_jumpers no)
		(fp_rect
			(start 0.7239 1.9939)
			(end -0.7239 -0.2159)
			(stroke
				(width 0)
				(type default)
			)
			(fill no)
			(layer "B.CrtYd")
		)
		(fp_line
			(start -0.7239 1.9939)
			(end -0.7239 -0.2159)
			(stroke
				(width 0.1)
				(type default)
			)
			(layer "B.Fab")
		)
		(fp_line
			(start 0.7239 1.9939)
			(end -0.7239 1.9939)
			(stroke
				(width 0.1)
				(type default)
			)
			(layer "B.Fab")
		)
		(fp_line
			(start -0.7239 -0.2159)
			(end 0.7239 -0.2159)
			(stroke
				(width 0.1)
				(type default)
			)
			(layer "B.Fab")
		)
		(fp_line
			(start 0.7239 -0.2159)
			(end 0.7239 1.9939)
			(stroke
				(width 0.1)
				(type default)
			)
			(layer "B.Fab")
		)
		(pad "1" smd rect
			(at 0 0 90)
			(size 1.27 1.016)
			(layers "B.Cu" "B.Mask" "B.Paste")
			(net "P12V_NVDIMM_ABC")
		)
		(pad "2" smd rect
			(at 0 1.778 90)
			(size 1.27 1.016)
			(layers "B.Cu" "B.Mask" "B.Paste")
			(net "GND")
		)
		(zone
			(layer "B.Cu")
			(hatch none 0.5)
			(connect_pads
				(clearance 0)
			)
			(min_thickness 0.25)
			(keepout
				(tracks not_allowed)
				(vias allowed)
				(pads allowed)
				(copperpour not_allowed)
				(footprints allowed)
			)
			(placement
				(enabled no)
				(sheetname "")
			)
			(fill
				(thermal_gap 0.5)
				(thermal_bridge_width 0.5)
				(island_removal_mode 0)
			)
			(polygon
				(pts
					(xy 191.822832 -17.088612) (xy 192.584832 -17.088612) (xy 192.584832 -18.358612) (xy 191.822832 -18.358612)
				)
			)
		)
	)
	(footprint ""
		(layer "B.Cu")
		(at 94.638368 1.47574 90)
		(property "Reference" "C8U10"
			(at -1.47828 0.78994 180)
			(unlocked yes)
			(layer "B.SilkS")
			(effects
				(font
					(size 0.4064 0.254)
					(thickness 0.1524)
				)
				(justify mirror)
			)
		)
		(property "Value" ""
			(at 0 0 90)
			(layer "B.Fab")
			(effects
				(font
					(size 1.27 1.27)
				)
				(justify mirror)
			)
		)
		(duplicate_pad_numbers_are_jumpers no)
		(fp_poly
			(pts
				(xy 0.7239 -0.2159) (xy -0.7239 -0.2159) (xy -0.7239 1.9939) (xy 0.7239 1.9939)
			)
			(stroke
				(width 0)
				(type default)
			)
			(fill no)
			(layer "B.CrtYd")
		)
		(fp_line
			(start 0.7239 -0.2159)
			(end 0.7239 1.9939)
			(stroke
				(width 0.1)
				(type default)
			)
			(layer "B.Fab")
		)
		(fp_line
			(start -0.7239 -0.2159)
			(end 0.7239 -0.2159)
			(stroke
				(width 0.1)
				(type default)
			)
			(layer "B.Fab")
		)
		(fp_line
			(start 0.7239 1.9939)
			(end -0.7239 1.9939)
			(stroke
				(width 0.1)
				(type default)
			)
			(layer "B.Fab")
		)
		(fp_line
			(start -0.7239 1.9939)
			(end -0.7239 -0.2159)
			(stroke
				(width 0.1)
				(type default)
			)
			(layer "B.Fab")
		)
		(pad "1" smd rect
			(at 0 0 270)
			(size 1.27 1.016)
			(layers "B.Cu" "B.Mask" "B.Paste")
			(net "PVTT_GHJ")
		)
		(pad "2" smd rect
			(at 0 1.778 270)
			(size 1.27 1.016)
			(layers "B.Cu" "B.Mask" "B.Paste")
			(net "GND")
		)
		(zone
			(layer "B.Cu")
			(hatch none 0.5)
			(connect_pads
				(clearance 0)
			)
			(min_thickness 0.25)
			(keepout
				(tracks not_allowed)
				(vias allowed)
				(pads allowed)
				(copperpour not_allowed)
				(footprints allowed)
			)
			(placement
				(enabled no)
				(sheetname "")
			)
			(fill
				(thermal_gap 0.5)
				(thermal_bridge_width 0.5)
				(island_removal_mode 0)
			)
			(polygon
				(pts
					(xy 95.146368 0.84074) (xy 95.146368 2.11074) (xy 95.908368 2.11074) (xy 95.908368 0.84074)
				)
			)
		)
	)
	(footprint ""
		(layer "B.Cu")
		(at 351.507806 -61.257434)
		(property "Reference" "C2U16"
			(at 0 0 0)
			(layer "B.SilkS")
			(hide yes)
			(effects
				(font
					(size 1.27 1.27)
				)
				(justify mirror)
			)
		)
		(property "Value" ""
			(at 0 0 0)
			(layer "B.Fab")
			(effects
				(font
					(size 1.27 1.27)
				)
				(justify mirror)
			)
		)
		(duplicate_pad_numbers_are_jumpers no)
		(fp_poly
			(pts
				(xy -0.3048 -0.1016) (xy -0.3048 0.9906) (xy 0.3048 0.9906) (xy 0.3048 -0.1016)
			)
			(stroke
				(width 0)
				(type default)
			)
			(fill no)
			(layer "B.CrtYd")
		)
		(fp_line
			(start -0.3048 -0.1016)
			(end 0.3048 -0.1016)
			(stroke
				(width 0.1)
				(type default)
			)
			(layer "B.Fab")
		)
		(fp_line
			(start -0.3048 0.9906)
			(end -0.3048 -0.1016)
			(stroke
				(width 0.1)
				(type default)
			)
			(layer "B.Fab")
		)
		(fp_line
			(start 0.3048 -0.1016)
			(end 0.3048 0.9906)
			(stroke
				(width 0.1)
				(type default)
			)
			(layer "B.Fab")
		)
		(fp_line
			(start 0.3048 0.9906)
			(end -0.3048 0.9906)
			(stroke
				(width 0.1)
				(type default)
			)
			(layer "B.Fab")
		)
		(pad "1" smd rect
			(at 0 0 180)
			(size 0.508 0.508)
			(layers "B.Cu" "B.Mask" "B.Paste")
			(net "P3E_CPU0_PE1_PCH_RXN<6>")
		)
		(pad "2" smd rect
			(at 0 0.889 180)
			(size 0.508 0.508)
			(layers "B.Cu" "B.Mask" "B.Paste")
			(net "P3E_CPU0_PE1_SS_RXN<6>")
		)
		(zone
			(layer "B.Cu")
			(hatch none 0.5)
			(connect_pads
				(clearance 0)
			)
			(min_thickness 0.25)
			(keepout
				(tracks allowed)
				(vias not_allowed)
				(pads allowed)
				(copperpour not_allowed)
				(footprints allowed)
			)
			(placement
				(enabled no)
				(sheetname "")
			)
			(fill
				(thermal_gap 0.5)
				(thermal_bridge_width 0.5)
				(island_removal_mode 0)
			)
			(polygon
				(pts
					(xy 351.761806 -61.003434) (xy 351.253806 -61.003434) (xy 351.253806 -60.622434) (xy 351.761806 -60.622434)
				)
			)
		)
		(zone
			(layer "B.Cu")
			(hatch none 0.5)
			(connect_pads
				(clearance 0)
			)
			(min_thickness 0.25)
			(keepout
				(tracks not_allowed)
				(vias allowed)
				(pads allowed)
				(copperpour not_allowed)
				(footprints allowed)
			)
			(placement
				(enabled no)
				(sheetname "")
			)
			(fill
				(thermal_gap 0.5)
				(thermal_bridge_width 0.5)
				(island_removal_mode 0)
			)
			(polygon
				(pts
					(xy 351.761806 -60.622434) (xy 351.253806 -60.622434) (xy 351.253806 -61.003434) (xy 351.761806 -61.003434)
				)
			)
		)
	)
)
